(kicad_pcb
	(version 20260206)
	(generator "pcbnew")
	(generator_version "10.0")
	(general
		(thickness 1.6)
		(legacy_teardrops no)
	)
	(paper "A4")
	(title_block
		(title "01162023_DA0F0TEBIF0_F0T_Expander_BD_F_brd_V02_OCP.brd")
		(comment 1 "Grand Teton / footprints 4401-4407 of 9728")
	)
	(layers
		(0 "F.Cu" signal "TOP")
		(4 "In1.Cu" signal "GND")
		(6 "In2.Cu" signal "VCC")
		(8 "In3.Cu" signal "VCC1")
		(10 "In4.Cu" signal "GND1")
		(12 "In5.Cu" signal "IN1")
		(14 "In6.Cu" signal "GND2")
		(16 "In7.Cu" signal "IN2")
		(18 "In8.Cu" signal "GND3")
		(20 "In9.Cu" signal "IN3")
		(22 "In10.Cu" signal "GND4")
		(24 "In11.Cu" signal "IN4")
		(26 "In12.Cu" signal "GND5")
		(28 "In13.Cu" signal "IN5")
		(30 "In14.Cu" signal "GND6")
		(32 "In15.Cu" signal "IN6")
		(34 "In16.Cu" signal "GND7")
		(2 "B.Cu" signal "BOTTOM")
		(9 "F.Adhes" user "F.Adhesive")
		(11 "B.Adhes" user "B.Adhesive")
		(13 "F.Paste" user "Package Geometry/Pastemask Top")
		(15 "B.Paste" user "Package Geometry/Pastemask Bottom")
		(5 "F.SilkS" user "Ref Des/Silkscreen Top")
		(7 "B.SilkS" user "Ref Des/Silkscreen Bottom")
		(1 "F.Mask" user "Board Geometry/Soldermask Top")
		(3 "B.Mask" user "Board Geometry/Soldermask Bottom")
		(17 "Dwgs.User" user "User.Drawings")
		(19 "Cmts.User" user "User.Comments")
		(21 "Eco1.User" user "User.Eco1")
		(23 "Eco2.User" user "User.Eco2")
		(25 "Edge.Cuts" user "Board Geometry/Outline")
		(27 "Margin" user)
		(31 "F.CrtYd" user "Package Geometry/Place Bound Top")
		(29 "B.CrtYd" user "Package Geometry/Place Bound Bottom")
		(35 "F.Fab" user "Ref Des/Assembly Top")
		(33 "B.Fab" user "Ref Des/Assembly Bottom")
	)
	(footprint ""
		(layer "F.Cu")
		(at 278.874982 -56.977534 180)
		(property "Reference" "PC414"
			(at 0 0 180)
			(layer "F.SilkS")
			(hide yes)
			(effects
				(font
					(size 1.27 1.27)
				)
			)
		)
		(property "Value" ""
			(at 0 0 180)
			(layer "F.Fab")
			(effects
				(font
					(size 1.27 1.27)
				)
			)
		)
		(duplicate_pad_numbers_are_jumpers no)
		(fp_line
			(start 0.7874 0.4064)
			(end -0.7874 0.4064)
			(stroke
				(width 0.1524)
				(type default)
			)
			(layer "F.SilkS")
		)
		(fp_line
			(start 0.7874 -0.4064)
			(end 0.7874 0.4064)
			(stroke
				(width 0.1524)
				(type default)
			)
			(layer "F.SilkS")
		)
		(fp_line
			(start -0.7874 0.4064)
			(end -0.7874 -0.4064)
			(stroke
				(width 0.1524)
				(type default)
			)
			(layer "F.SilkS")
		)
		(fp_line
			(start -0.7874 -0.4064)
			(end 0.7874 -0.4064)
			(stroke
				(width 0.1524)
				(type default)
			)
			(layer "F.SilkS")
		)
		(fp_line
			(start 0.67945 0.3048)
			(end 0.120396 0.3048)
			(stroke
				(width 0.1)
				(type default)
			)
			(layer "F.Fab")
		)
		(fp_line
			(start 0.67945 -0.3048)
			(end 0.67945 0.3048)
			(stroke
				(width 0.1)
				(type default)
			)
			(layer "F.Fab")
		)
		(fp_line
			(start 0.12065 -0.2794)
			(end 0.12065 -0.3048)
			(stroke
				(width 0.1)
				(type default)
			)
			(layer "F.Fab")
		)
		(fp_line
			(start 0.12065 -0.3048)
			(end 0.67945 -0.3048)
			(stroke
				(width 0.1)
				(type default)
			)
			(layer "F.Fab")
		)
		(fp_line
			(start 0.120396 0.3048)
			(end 0.120396 0.2794)
			(stroke
				(width 0.1)
				(type default)
			)
			(layer "F.Fab")
		)
		(fp_line
			(start 0.120396 0.2794)
			(end -0.12065 0.2794)
			(stroke
				(width 0.1)
				(type default)
			)
			(layer "F.Fab")
		)
		(fp_line
			(start -0.12065 0.3048)
			(end -0.67945 0.3048)
			(stroke
				(width 0.1)
				(type default)
			)
			(layer "F.Fab")
		)
		(fp_line
			(start -0.12065 0.2794)
			(end -0.12065 0.3048)
			(stroke
				(width 0.1)
				(type default)
			)
			(layer "F.Fab")
		)
		(fp_line
			(start -0.12065 -0.2794)
			(end 0.12065 -0.2794)
			(stroke
				(width 0.1)
				(type default)
			)
			(layer "F.Fab")
		)
		(fp_line
			(start -0.12065 -0.305054)
			(end -0.12065 -0.2794)
			(stroke
				(width 0.1)
				(type default)
			)
			(layer "F.Fab")
		)
		(fp_line
			(start -0.67945 0.3048)
			(end -0.67945 -0.305054)
			(stroke
				(width 0.1)
				(type default)
			)
			(layer "F.Fab")
		)
		(fp_line
			(start -0.67945 -0.305054)
			(end -0.12065 -0.305054)
			(stroke
				(width 0.1)
				(type default)
			)
			(layer "F.Fab")
		)
		(pad "1" smd circle
			(at -0.40005 0 180)
			(size 0 0)
			(layers "F.Cu" "F.Mask" "F.Paste")
			(net "P12V_AUX")
		)
		(pad "2" smd circle
			(at 0.40005 0 180)
			(size 0 0)
			(layers "F.Cu" "F.Mask" "F.Paste")
			(net "GND")
		)
	)
	(footprint ""
		(layer "F.Cu")
		(at 210.59394 -114.886486)
		(property "Reference" "PR7012"
			(at 0 0 0)
			(layer "F.SilkS")
			(hide yes)
			(effects
				(font
					(size 1.27 1.27)
				)
			)
		)
		(property "Value" ""
			(at 0 0 0)
			(layer "F.Fab")
			(effects
				(font
					(size 1.27 1.27)
				)
			)
		)
		(duplicate_pad_numbers_are_jumpers no)
		(fp_line
			(start -0.7874 -0.4064)
			(end 0.7874 -0.4064)
			(stroke
				(width 0.1524)
				(type default)
			)
			(layer "F.SilkS")
		)
		(fp_line
			(start -0.7874 0.4064)
			(end -0.7874 -0.4064)
			(stroke
				(width 0.1524)
				(type default)
			)
			(layer "F.SilkS")
		)
		(fp_line
			(start 0.7874 -0.4064)
			(end 0.7874 0.4064)
			(stroke
				(width 0.1524)
				(type default)
			)
			(layer "F.SilkS")
		)
		(fp_line
			(start 0.7874 0.4064)
			(end -0.7874 0.4064)
			(stroke
				(width 0.1524)
				(type default)
			)
			(layer "F.SilkS")
		)
		(fp_line
			(start -0.67945 -0.305054)
			(end -0.12065 -0.305054)
			(stroke
				(width 0.1)
				(type default)
			)
			(layer "F.Fab")
		)
		(fp_line
			(start -0.67945 0.3048)
			(end -0.67945 -0.305054)
			(stroke
				(width 0.1)
				(type default)
			)
			(layer "F.Fab")
		)
		(fp_line
			(start -0.12065 -0.305054)
			(end -0.12065 -0.2794)
			(stroke
				(width 0.1)
				(type default)
			)
			(layer "F.Fab")
		)
		(fp_line
			(start -0.12065 -0.2794)
			(end 0.12065 -0.2794)
			(stroke
				(width 0.1)
				(type default)
			)
			(layer "F.Fab")
		)
		(fp_line
			(start -0.12065 0.2794)
			(end -0.12065 0.3048)
			(stroke
				(width 0.1)
				(type default)
			)
			(layer "F.Fab")
		)
		(fp_line
			(start -0.12065 0.3048)
			(end -0.67945 0.3048)
			(stroke
				(width 0.1)
				(type default)
			)
			(layer "F.Fab")
		)
		(fp_line
			(start 0.120396 0.2794)
			(end -0.12065 0.2794)
			(stroke
				(width 0.1)
				(type default)
			)
			(layer "F.Fab")
		)
		(fp_line
			(start 0.120396 0.3048)
			(end 0.120396 0.2794)
			(stroke
				(width 0.1)
				(type default)
			)
			(layer "F.Fab")
		)
		(fp_line
			(start 0.12065 -0.3048)
			(end 0.67945 -0.3048)
			(stroke
				(width 0.1)
				(type default)
			)
			(layer "F.Fab")
		)
		(fp_line
			(start 0.12065 -0.2794)
			(end 0.12065 -0.3048)
			(stroke
				(width 0.1)
				(type default)
			)
			(layer "F.Fab")
		)
		(fp_line
			(start 0.67945 -0.3048)
			(end 0.67945 0.3048)
			(stroke
				(width 0.1)
				(type default)
			)
			(layer "F.Fab")
		)
		(fp_line
			(start 0.67945 0.3048)
			(end 0.120396 0.3048)
			(stroke
				(width 0.1)
				(type default)
			)
			(layer "F.Fab")
		)
		(pad "1" smd circle
			(at -0.40005 0)
			(size 0 0)
			(layers "F.Cu" "F.Mask" "F.Paste")
			(net "P3V3_NIC3_CO_MODE")
		)
		(pad "2" smd circle
			(at 0.40005 0)
			(size 0 0)
			(layers "F.Cu" "F.Mask" "F.Paste")
			(net "GND")
		)
	)
	(footprint ""
		(layer "F.Cu")
		(at 188.355224 -35.876738)
		(property "Reference" "R6069"
			(at 0 0 0)
			(layer "F.SilkS")
			(hide yes)
			(effects
				(font
					(size 1.27 1.27)
				)
			)
		)
		(property "Value" ""
			(at 0 0 0)
			(layer "F.Fab")
			(effects
				(font
					(size 1.27 1.27)
				)
			)
		)
		(duplicate_pad_numbers_are_jumpers no)
		(fp_line
			(start -0.7874 -0.4064)
			(end 0.7874 -0.4064)
			(stroke
				(width 0.1524)
				(type default)
			)
			(layer "F.SilkS")
		)
		(fp_line
			(start -0.7874 0.4064)
			(end -0.7874 -0.4064)
			(stroke
				(width 0.1524)
				(type default)
			)
			(layer "F.SilkS")
		)
		(fp_line
			(start 0.7874 -0.4064)
			(end 0.7874 0.4064)
			(stroke
				(width 0.1524)
				(type default)
			)
			(layer "F.SilkS")
		)
		(fp_line
			(start 0.7874 0.4064)
			(end -0.7874 0.4064)
			(stroke
				(width 0.1524)
				(type default)
			)
			(layer "F.SilkS")
		)
		(fp_line
			(start -0.67945 -0.305054)
			(end -0.12065 -0.305054)
			(stroke
				(width 0.1)
				(type default)
			)
			(layer "F.Fab")
		)
		(fp_line
			(start -0.67945 0.3048)
			(end -0.67945 -0.305054)
			(stroke
				(width 0.1)
				(type default)
			)
			(layer "F.Fab")
		)
		(fp_line
			(start -0.12065 -0.305054)
			(end -0.12065 -0.2794)
			(stroke
				(width 0.1)
				(type default)
			)
			(layer "F.Fab")
		)
		(fp_line
			(start -0.12065 -0.2794)
			(end 0.12065 -0.2794)
			(stroke
				(width 0.1)
				(type default)
			)
			(layer "F.Fab")
		)
		(fp_line
			(start -0.12065 0.2794)
			(end -0.12065 0.3048)
			(stroke
				(width 0.1)
				(type default)
			)
			(layer "F.Fab")
		)
		(fp_line
			(start -0.12065 0.3048)
			(end -0.67945 0.3048)
			(stroke
				(width 0.1)
				(type default)
			)
			(layer "F.Fab")
		)
		(fp_line
			(start 0.120396 0.2794)
			(end -0.12065 0.2794)
			(stroke
				(width 0.1)
				(type default)
			)
			(layer "F.Fab")
		)
		(fp_line
			(start 0.120396 0.3048)
			(end 0.120396 0.2794)
			(stroke
				(width 0.1)
				(type default)
			)
			(layer "F.Fab")
		)
		(fp_line
			(start 0.12065 -0.3048)
			(end 0.67945 -0.3048)
			(stroke
				(width 0.1)
				(type default)
			)
			(layer "F.Fab")
		)
		(fp_line
			(start 0.12065 -0.2794)
			(end 0.12065 -0.3048)
			(stroke
				(width 0.1)
				(type default)
			)
			(layer "F.Fab")
		)
		(fp_line
			(start 0.67945 -0.3048)
			(end 0.67945 0.3048)
			(stroke
				(width 0.1)
				(type default)
			)
			(layer "F.Fab")
		)
		(fp_line
			(start 0.67945 0.3048)
			(end 0.120396 0.3048)
			(stroke
				(width 0.1)
				(type default)
			)
			(layer "F.Fab")
		)
		(pad "1" smd circle
			(at -0.40005 0)
			(size 0 0)
			(layers "F.Cu" "F.Mask" "F.Paste")
			(net "P3V3_AUX")
		)
		(pad "2" smd circle
			(at 0.40005 0)
			(size 0 0)
			(layers "F.Cu" "F.Mask" "F.Paste")
			(net "PWRGD_P3V3_SSD7_D")
		)
	)
	(footprint ""
		(layer "F.Cu")
		(at 275.992336 -28.225242 180)
		(property "Reference" "C502"
			(at 0 0 180)
			(layer "F.SilkS")
			(hide yes)
			(effects
				(font
					(size 1.27 1.27)
				)
			)
		)
		(property "Value" ""
			(at 0 0 180)
			(layer "F.Fab")
			(effects
				(font
					(size 1.27 1.27)
				)
			)
		)
		(duplicate_pad_numbers_are_jumpers no)
		(fp_line
			(start 0.299974 0.150114)
			(end -0.299974 0.150114)
			(stroke
				(width 0.1)
				(type default)
			)
			(layer "F.Fab")
		)
		(fp_line
			(start 0.299974 -0.150114)
			(end 0.299974 0.150114)
			(stroke
				(width 0.1)
				(type default)
			)
			(layer "F.Fab")
		)
		(fp_line
			(start -0.299974 0.150114)
			(end -0.299974 -0.150114)
			(stroke
				(width 0.1)
				(type default)
			)
			(layer "F.Fab")
		)
		(fp_line
			(start -0.299974 -0.150114)
			(end 0.299974 -0.150114)
			(stroke
				(width 0.1)
				(type default)
			)
			(layer "F.Fab")
		)
		(pad "1" smd rect
			(at -0.2667 0 180)
			(size 0.3048 0.381)
			(layers "F.Cu" "F.Mask" "F.Paste")
			(net "P5E_PEX2_STN2_TX_DN<40>")
		)
		(pad "2" smd rect
			(at 0.2667 0 180)
			(size 0.3048 0.381)
			(layers "F.Cu" "F.Mask" "F.Paste")
			(net "P5E_PEX2_STN2_TX_C_DN<40>")
		)
	)
	(footprint ""
		(layer "F.Cu")
		(at 445.826642 -55.418228 90)
		(property "Reference" "PC442"
			(at 0 0 90)
			(layer "F.SilkS")
			(hide yes)
			(effects
				(font
					(size 1.27 1.27)
				)
			)
		)
		(property "Value" ""
			(at 0 0 90)
			(layer "F.Fab")
			(effects
				(font
					(size 1.27 1.27)
				)
			)
		)
		(duplicate_pad_numbers_are_jumpers no)
		(fp_line
			(start 0.7874 -0.4064)
			(end 0.7874 0.4064)
			(stroke
				(width 0.1524)
				(type default)
			)
			(layer "F.SilkS")
		)
		(fp_line
			(start -0.7874 -0.4064)
			(end 0.7874 -0.4064)
			(stroke
				(width 0.1524)
				(type default)
			)
			(layer "F.SilkS")
		)
		(fp_line
			(start 0.7874 0.4064)
			(end -0.7874 0.4064)
			(stroke
				(width 0.1524)
				(type default)
			)
			(layer "F.SilkS")
		)
		(fp_line
			(start -0.7874 0.4064)
			(end -0.7874 -0.4064)
			(stroke
				(width 0.1524)
				(type default)
			)
			(layer "F.SilkS")
		)
		(fp_line
			(start -0.12065 -0.305054)
			(end -0.12065 -0.2794)
			(stroke
				(width 0.1)
				(type default)
			)
			(layer "F.Fab")
		)
		(fp_line
			(start -0.67945 -0.305054)
			(end -0.12065 -0.305054)
			(stroke
				(width 0.1)
				(type default)
			)
			(layer "F.Fab")
		)
		(fp_line
			(start 0.67945 -0.3048)
			(end 0.67945 0.3048)
			(stroke
				(width 0.1)
				(type default)
			)
			(layer "F.Fab")
		)
		(fp_line
			(start 0.12065 -0.3048)
			(end 0.67945 -0.3048)
			(stroke
				(width 0.1)
				(type default)
			)
			(layer "F.Fab")
		)
		(fp_line
			(start 0.12065 -0.2794)
			(end 0.12065 -0.3048)
			(stroke
				(width 0.1)
				(type default)
			)
			(layer "F.Fab")
		)
		(fp_line
			(start -0.12065 -0.2794)
			(end 0.12065 -0.2794)
			(stroke
				(width 0.1)
				(type default)
			)
			(layer "F.Fab")
		)
		(fp_line
			(start 0.120396 0.2794)
			(end -0.12065 0.2794)
			(stroke
				(width 0.1)
				(type default)
			)
			(layer "F.Fab")
		)
		(fp_line
			(start -0.12065 0.2794)
			(end -0.12065 0.3048)
			(stroke
				(width 0.1)
				(type default)
			)
			(layer "F.Fab")
		)
		(fp_line
			(start 0.67945 0.3048)
			(end 0.120396 0.3048)
			(stroke
				(width 0.1)
				(type default)
			)
			(layer "F.Fab")
		)
		(fp_line
			(start 0.120396 0.3048)
			(end 0.120396 0.2794)
			(stroke
				(width 0.1)
				(type default)
			)
			(layer "F.Fab")
		)
		(fp_line
			(start -0.12065 0.3048)
			(end -0.67945 0.3048)
			(stroke
				(width 0.1)
				(type default)
			)
			(layer "F.Fab")
		)
		(fp_line
			(start -0.67945 0.3048)
			(end -0.67945 -0.305054)
			(stroke
				(width 0.1)
				(type default)
			)
			(layer "F.Fab")
		)
		(pad "1" smd circle
			(at -0.40005 0 90)
			(size 0 0)
			(layers "F.Cu" "F.Mask" "F.Paste")
			(net "P12V_SSD15_R")
		)
		(pad "2" smd circle
			(at 0.40005 0 90)
			(size 0 0)
			(layers "F.Cu" "F.Mask" "F.Paste")
			(net "GND")
		)
	)
	(footprint ""
		(layer "F.Cu")
		(at 228.980746 -118.984268 90)
		(property "Reference" "PR6891"
			(at 0 0 90)
			(layer "F.SilkS")
			(hide yes)
			(effects
				(font
					(size 1.27 1.27)
				)
			)
		)
		(property "Value" ""
			(at 0 0 90)
			(layer "F.Fab")
			(effects
				(font
					(size 1.27 1.27)
				)
			)
		)
		(duplicate_pad_numbers_are_jumpers no)
		(fp_line
			(start 1.2954 -0.5842)
			(end 1.2954 0.5842)
			(stroke
				(width 0.1524)
				(type default)
			)
			(layer "F.SilkS")
		)
		(fp_line
			(start -1.2954 -0.5842)
			(end 1.2954 -0.5842)
			(stroke
				(width 0.1524)
				(type default)
			)
			(layer "F.SilkS")
		)
		(fp_line
			(start 1.2954 0.5842)
			(end -1.2954 0.5842)
			(stroke
				(width 0.1524)
				(type default)
			)
			(layer "F.SilkS")
		)
		(fp_line
			(start -1.2954 0.5842)
			(end -1.2954 -0.5842)
			(stroke
				(width 0.1524)
				(type default)
			)
			(layer "F.SilkS")
		)
		(fp_line
			(start 0.8636 -0.4572)
			(end 0.8636 -0.406654)
			(stroke
				(width 0.1)
				(type default)
			)
			(layer "F.Fab")
		)
		(fp_line
			(start -0.8636 -0.4572)
			(end 0.8636 -0.4572)
			(stroke
				(width 0.1)
				(type default)
			)
			(layer "F.Fab")
		)
		(fp_line
			(start 1.1938 -0.406654)
			(end 1.1938 0.4064)
			(stroke
				(width 0.1)
				(type default)
			)
			(layer "F.Fab")
		)
		(fp_line
			(start 0.8636 -0.406654)
			(end 1.1938 -0.406654)
			(stroke
				(width 0.1)
				(type default)
			)
			(layer "F.Fab")
		)
		(fp_line
			(start -0.8636 -0.406654)
			(end -0.8636 -0.4572)
			(stroke
				(width 0.1)
				(type default)
			)
			(layer "F.Fab")
		)
		(fp_line
			(start -1.1938 -0.406654)
			(end -0.8636 -0.406654)
			(stroke
				(width 0.1)
				(type default)
			)
			(layer "F.Fab")
		)
		(fp_line
			(start 1.1938 0.4064)
			(end 0.8636 0.4064)
			(stroke
				(width 0.1)
				(type default)
			)
			(layer "F.Fab")
		)
		(fp_line
			(start 0.8636 0.4064)
			(end 0.8636 0.4572)
			(stroke
				(width 0.1)
				(type default)
			)
			(layer "F.Fab")
		)
		(fp_line
			(start -0.8636 0.4064)
			(end -1.1938 0.4064)
			(stroke
				(width 0.1)
				(type default)
			)
			(layer "F.Fab")
		)
		(fp_line
			(start -1.1938 0.4064)
			(end -1.1938 -0.406654)
			(stroke
				(width 0.1)
				(type default)
			)
			(layer "F.Fab")
		)
		(fp_line
			(start -0.8636 0.4318)
			(end -0.8636 0.4064)
			(stroke
				(width 0.1)
				(type default)
			)
			(layer "F.Fab")
		)
		(fp_line
			(start 0.8636 0.4572)
			(end -0.8636 0.4572)
			(stroke
				(width 0.1)
				(type default)
			)
			(layer "F.Fab")
		)
		(fp_line
			(start -0.8636 0.4572)
			(end -0.8636 0.4318)
			(stroke
				(width 0.1)
				(type default)
			)
			(layer "F.Fab")
		)
		(pad "1" smd rect
			(at -0.7366 0)
			(size 0.7112 0.8128)
			(layers "F.Cu" "F.Mask" "F.Paste")
			(net "P12V_NIC3_CO_AVIN_PD")
		)
		(pad "2" smd rect
			(at 0.7366 0)
			(size 0.7112 0.8128)
			(layers "F.Cu" "F.Mask" "F.Paste")
			(net "P12V_AUX")
		)
	)
	(footprint ""
		(layer "F.Cu")
		(at 238.208312 -226.368864)
		(property "Reference" "R6594"
			(at 0 0 0)
			(layer "F.SilkS")
			(hide yes)
			(effects
				(font
					(size 1.27 1.27)
				)
			)
		)
		(property "Value" ""
			(at 0 0 0)
			(layer "F.Fab")
			(effects
				(font
					(size 1.27 1.27)
				)
			)
		)
		(duplicate_pad_numbers_are_jumpers no)
		(fp_line
			(start -0.7874 -0.4064)
			(end 0.7874 -0.4064)
			(stroke
				(width 0.1524)
				(type default)
			)
			(layer "F.SilkS")
		)
		(fp_line
			(start -0.7874 0.4064)
			(end -0.7874 -0.4064)
			(stroke
				(width 0.1524)
				(type default)
			)
			(layer "F.SilkS")
		)
		(fp_line
			(start 0.7874 -0.4064)
			(end 0.7874 0.4064)
			(stroke
				(width 0.1524)
				(type default)
			)
			(layer "F.SilkS")
		)
		(fp_line
			(start 0.7874 0.4064)
			(end -0.7874 0.4064)
			(stroke
				(width 0.1524)
				(type default)
			)
			(layer "F.SilkS")
		)
		(fp_line
			(start -0.67945 -0.305054)
			(end -0.12065 -0.305054)
			(stroke
				(width 0.1)
				(type default)
			)
			(layer "F.Fab")
		)
		(fp_line
			(start -0.67945 0.3048)
			(end -0.67945 -0.305054)
			(stroke
				(width 0.1)
				(type default)
			)
			(layer "F.Fab")
		)
		(fp_line
			(start -0.12065 -0.305054)
			(end -0.12065 -0.2794)
			(stroke
				(width 0.1)
				(type default)
			)
			(layer "F.Fab")
		)
		(fp_line
			(start -0.12065 -0.2794)
			(end 0.12065 -0.2794)
			(stroke
				(width 0.1)
				(type default)
			)
			(layer "F.Fab")
		)
		(fp_line
			(start -0.12065 0.2794)
			(end -0.12065 0.3048)
			(stroke
				(width 0.1)
				(type default)
			)
			(layer "F.Fab")
		)
		(fp_line
			(start -0.12065 0.3048)
			(end -0.67945 0.3048)
			(stroke
				(width 0.1)
				(type default)
			)
			(layer "F.Fab")
		)
		(fp_line
			(start 0.120396 0.2794)
			(end -0.12065 0.2794)
			(stroke
				(width 0.1)
				(type default)
			)
			(layer "F.Fab")
		)
		(fp_line
			(start 0.120396 0.3048)
			(end 0.120396 0.2794)
			(stroke
				(width 0.1)
				(type default)
			)
			(layer "F.Fab")
		)
		(fp_line
			(start 0.12065 -0.3048)
			(end 0.67945 -0.3048)
			(stroke
				(width 0.1)
				(type default)
			)
			(layer "F.Fab")
		)
		(fp_line
			(start 0.12065 -0.2794)
			(end 0.12065 -0.3048)
			(stroke
				(width 0.1)
				(type default)
			)
			(layer "F.Fab")
		)
		(fp_line
			(start 0.67945 -0.3048)
			(end 0.67945 0.3048)
			(stroke
				(width 0.1)
				(type default)
			)
			(layer "F.Fab")
		)
		(fp_line
			(start 0.67945 0.3048)
			(end 0.120396 0.3048)
			(stroke
				(width 0.1)
				(type default)
			)
			(layer "F.Fab")
		)
		(pad "1" smd circle
			(at -0.40005 0)
			(size 0 0)
			(layers "F.Cu" "F.Mask" "F.Paste")
			(net "P1V8_PLL0_PEX3")
		)
		(pad "2" smd circle
			(at 0.40005 0)
			(size 0 0)
			(layers "F.Cu" "F.Mask" "F.Paste")
			(net "P1V8_PLL0_PEX3_SCALED")
		)
	)
)
